(kicad_pcb
	(version 20260206)
	(generator "pcbnew")
	(generator_version "10.0")
	(general
		(thickness 1.6)
		(legacy_teardrops no)
	)
	(paper "A4")
	(title_block
		(title "01162023_DA0F0TEBIF0_F0T_Expander_BD_F_brd_V02_OCP.brd")
		(comment 1 "Grand Teton / footprints 4603-4605 of 9728")
	)
	(layers
		(0 "F.Cu" signal "TOP")
		(4 "In1.Cu" signal "GND")
		(6 "In2.Cu" signal "VCC")
		(8 "In3.Cu" signal "VCC1")
		(10 "In4.Cu" signal "GND1")
		(12 "In5.Cu" signal "IN1")
		(14 "In6.Cu" signal "GND2")
		(16 "In7.Cu" signal "IN2")
		(18 "In8.Cu" signal "GND3")
		(20 "In9.Cu" signal "IN3")
		(22 "In10.Cu" signal "GND4")
		(24 "In11.Cu" signal "IN4")
		(26 "In12.Cu" signal "GND5")
		(28 "In13.Cu" signal "IN5")
		(30 "In14.Cu" signal "GND6")
		(32 "In15.Cu" signal "IN6")
		(34 "In16.Cu" signal "GND7")
		(2 "B.Cu" signal "BOTTOM")
		(9 "F.Adhes" user "F.Adhesive")
		(11 "B.Adhes" user "B.Adhesive")
		(13 "F.Paste" user "Package Geometry/Pastemask Top")
		(15 "B.Paste" user "Package Geometry/Pastemask Bottom")
		(5 "F.SilkS" user "Ref Des/Silkscreen Top")
		(7 "B.SilkS" user "Ref Des/Silkscreen Bottom")
		(1 "F.Mask" user "Board Geometry/Soldermask Top")
		(3 "B.Mask" user "Board Geometry/Soldermask Bottom")
		(17 "Dwgs.User" user "User.Drawings")
		(19 "Cmts.User" user "User.Comments")
		(21 "Eco1.User" user "User.Eco1")
		(23 "Eco2.User" user "User.Eco2")
		(25 "Edge.Cuts" user "Board Geometry/Outline")
		(27 "Margin" user)
		(31 "F.CrtYd" user "Package Geometry/Place Bound Top")
		(29 "B.CrtYd" user "Package Geometry/Place Bound Bottom")
		(35 "F.Fab" user "Ref Des/Assembly Top")
		(33 "B.Fab" user "Ref Des/Assembly Bottom")
	)
	(footprint ""
		(layer "F.Cu")
		(at 211.892388 -32.739584 180)
		(property "Reference" "C302"
			(at 0 0 180)
			(layer "F.SilkS")
			(hide yes)
			(effects
				(font
					(size 1.27 1.27)
				)
			)
		)
		(property "Value" ""
			(at 0 0 180)
			(layer "F.Fab")
			(effects
				(font
					(size 1.27 1.27)
				)
			)
		)
		(duplicate_pad_numbers_are_jumpers no)
		(fp_line
			(start 0.299974 0.150114)
			(end -0.299974 0.150114)
			(stroke
				(width 0.1)
				(type default)
			)
			(layer "F.Fab")
		)
		(fp_line
			(start 0.299974 -0.150114)
			(end 0.299974 0.150114)
			(stroke
				(width 0.1)
				(type default)
			)
			(layer "F.Fab")
		)
		(fp_line
			(start -0.299974 0.150114)
			(end -0.299974 -0.150114)
			(stroke
				(width 0.1)
				(type default)
			)
			(layer "F.Fab")
		)
		(fp_line
			(start -0.299974 -0.150114)
			(end 0.299974 -0.150114)
			(stroke
				(width 0.1)
				(type default)
			)
			(layer "F.Fab")
		)
		(pad "1" smd rect
			(at -0.2667 0 180)
			(size 0.3048 0.381)
			(layers "F.Cu" "F.Mask" "F.Paste")
			(net "P5E_PEX1_STN2_TX_DP<34>")
		)
		(pad "2" smd rect
			(at 0.2667 0 180)
			(size 0.3048 0.381)
			(layers "F.Cu" "F.Mask" "F.Paste")
			(net "P5E_PEX1_STN2_TX_C_DP<34>")
		)
	)
	(footprint ""
		(layer "F.Cu")
		(at 271.895062 -343.952322 90)
		(property "Reference" "C612"
			(at 0 0 90)
			(layer "F.SilkS")
			(hide yes)
			(effects
				(font
					(size 1.27 1.27)
				)
			)
		)
		(property "Value" ""
			(at 0 0 90)
			(layer "F.Fab")
			(effects
				(font
					(size 1.27 1.27)
				)
			)
		)
		(duplicate_pad_numbers_are_jumpers no)
		(fp_line
			(start 0.299974 -0.150114)
			(end 0.299974 0.150114)
			(stroke
				(width 0.1)
				(type default)
			)
			(layer "F.Fab")
		)
		(fp_line
			(start -0.299974 -0.150114)
			(end 0.299974 -0.150114)
			(stroke
				(width 0.1)
				(type default)
			)
			(layer "F.Fab")
		)
		(fp_line
			(start 0.299974 0.150114)
			(end -0.299974 0.150114)
			(stroke
				(width 0.1)
				(type default)
			)
			(layer "F.Fab")
		)
		(fp_line
			(start -0.299974 0.150114)
			(end -0.299974 -0.150114)
			(stroke
				(width 0.1)
				(type default)
			)
			(layer "F.Fab")
		)
		(pad "1" smd rect
			(at -0.2667 0 90)
			(size 0.3048 0.381)
			(layers "F.Cu" "F.Mask" "F.Paste")
			(net "P5E_PEX2_STN7_TX_DN<113>")
		)
		(pad "2" smd rect
			(at 0.2667 0 90)
			(size 0.3048 0.381)
			(layers "F.Cu" "F.Mask" "F.Paste")
			(net "P5E_PEX2_STN7_TX_C_DN<113>")
		)
	)
	(footprint ""
		(layer "F.Cu")
		(at 291.090858 -55.663846 90)
		(property "Reference" "PU66"
			(at -1.23063 2.755392 90)
			(unlocked yes)
			(layer "F.SilkS")
			(effects
				(font
					(size 0.7874 0.5842)
					(thickness 0.1524)
				)
				(justify left)
			)
		)
		(property "Value" ""
			(at 0 0 90)
			(layer "F.Fab")
			(effects
				(font
					(size 1.27 1.27)
				)
			)
		)
		(duplicate_pad_numbers_are_jumpers no)
		(fp_line
			(start 1.943608 -1.549908)
			(end 1.943608 1.549908)
			(stroke
				(width 0.1524)
				(type default)
			)
			(layer "F.SilkS")
		)
		(fp_line
			(start -1.943608 -1.549908)
			(end 1.943608 -1.549908)
			(stroke
				(width 0.1524)
				(type default)
			)
			(layer "F.SilkS")
		)
		(fp_line
			(start 1.943608 1.549908)
			(end -1.943608 1.549908)
			(stroke
				(width 0.1524)
				(type default)
			)
			(layer "F.SilkS")
		)
		(fp_line
			(start -1.943608 1.549908)
			(end -1.943608 -1.549908)
			(stroke
				(width 0.1524)
				(type default)
			)
			(layer "F.SilkS")
		)
		(fp_poly
			(pts
				(xy -2.019808 -1.549908) (xy -1.257808 -1.549908) (xy -1.257808 -1.880108) (xy -2.019808 -1.880108)
			)
			(stroke
				(width 0)
				(type default)
			)
			(fill yes)
			(layer "F.SilkS")
		)
		(fp_line
			(start 1.549908 -1.549908)
			(end 1.549908 1.549908)
			(stroke
				(width 0.1)
				(type default)
			)
			(layer "F.Fab")
		)
		(fp_line
			(start -1.549908 -1.549908)
			(end 1.549908 -1.549908)
			(stroke
				(width 0.1)
				(type default)
			)
			(layer "F.Fab")
		)
		(fp_line
			(start 1.549908 1.549908)
			(end -1.549908 1.549908)
			(stroke
				(width 0.1)
				(type default)
			)
			(layer "F.Fab")
		)
		(fp_line
			(start -1.549908 1.549908)
			(end -1.549908 -1.549908)
			(stroke
				(width 0.1)
				(type default)
			)
			(layer "F.Fab")
		)
		(fp_poly
			(pts
				(xy -2.019808 -1.549908) (xy -1.257808 -1.549908) (xy -1.257808 -1.880108) (xy -2.019808 -1.880108)
			)
			(stroke
				(width 0)
				(type default)
			)
			(fill yes)
			(layer "F.Fab")
		)
		(pad "1" smd rect
			(at -1.500124 -1.249934)
			(size 0.2794 0.6096)
			(layers "F.Cu" "F.Mask" "F.Paste")
			(net "P3V3_SSD10")
		)
		(pad "2" smd rect
			(at -1.500124 -0.750062)
			(size 0.2794 0.6096)
			(layers "F.Cu" "F.Mask" "F.Paste")
			(net "P3V3_SSD10")
		)
		(pad "3" smd rect
			(at -1.500124 -0.249936)
			(size 0.2794 0.6096)
			(layers "F.Cu" "F.Mask" "F.Paste")
			(net "P3V3_SSD10")
		)
		(pad "4" smd rect
			(at -1.500124 0.249936)
			(size 0.2794 0.6096)
			(layers "F.Cu" "F.Mask" "F.Paste")
			(net "P3V3_SSD10")
		)
		(pad "5" smd rect
			(at -1.500124 0.750062)
			(size 0.2794 0.6096)
			(layers "F.Cu" "F.Mask" "F.Paste")
			(net "P3V3_SSD10")
		)
		(pad "6" smd rect
			(at -1.500124 1.249934)
			(size 0.2794 0.6096)
			(layers "F.Cu" "F.Mask" "F.Paste")
			(net "GND")
		)
		(pad "7" smd rect
			(at 1.500124 1.249934)
			(size 0.2794 0.6096)
			(layers "F.Cu" "F.Mask" "F.Paste")
			(net "P3V3_SSD10_SS")
		)
		(pad "8" smd rect
			(at 1.500124 0.750062)
			(size 0.2794 0.6096)
			(layers "F.Cu" "F.Mask" "F.Paste")
			(net "PWRGD_P3V3_SSD10")
		)
		(pad "9" smd rect
			(at 1.500124 0.249936)
			(size 0.2794 0.6096)
			(layers "F.Cu" "F.Mask" "F.Paste")
			(net "P3V3_SSD10_OCP")
		)
		(pad "10" smd rect
			(at 1.500124 -0.249936)
			(size 0.2794 0.6096)
			(layers "F.Cu" "F.Mask" "F.Paste")
			(net "P5V_AUX")
		)
		(pad "11" smd rect
			(at 1.500124 -0.750062)
			(size 0.2794 0.6096)
			(layers "F.Cu" "F.Mask" "F.Paste")
			(net "SSD10_AUX_P3V3_EN_R")
		)
		(pad "12" smd rect
			(at 1.500124 -1.249934)
			(size 0.2794 0.6096)
			(layers "F.Cu" "F.Mask" "F.Paste")
			(net "P3V3_AUX")
		)
		(pad "13" smd rect
			(at 0 0 90)
			(size 1.9812 2.7178)
			(layers "F.Cu" "F.Mask" "F.Paste")
			(net "P3V3_AUX")
		)
		(zone
			(layer "F.Cu")
			(hatch none 0.5)
			(connect_pads
				(clearance 0)
			)
			(min_thickness 0.25)
			(keepout
				(tracks not_allowed)
				(vias allowed)
				(pads allowed)
				(copperpour not_allowed)
				(footprints allowed)
			)
			(placement
				(enabled no)
				(sheetname "")
			)
			(fill
				(thermal_gap 0.5)
				(thermal_bridge_width 0.5)
				(island_removal_mode 0)
			)
			(polygon
				(pts
					(xy 289.541458 -56.806846) (xy 289.668458 -56.806846) (xy 292.640258 -56.806846) (xy 292.640766 -56.806846)
					(xy 292.640766 -54.520846) (xy 292.640258 -54.520846) (xy 292.513258 -54.520846) (xy 291.090858 -54.520846)
					(xy 291.090858 -54.622446) (xy 292.513258 -54.622446) (xy 292.513258 -56.705246) (xy 289.668458 -56.705246)
					(xy 289.668458 -54.622446) (xy 291.065458 -54.622446) (xy 291.065458 -54.520846) (xy 289.668458 -54.520846)
					(xy 289.541458 -54.520846) (xy 289.54095 -54.520846) (xy 289.54095 -56.806846)
				)
			)
		)
	)
)
